# T6G (Grand Teton) — schematic netlist excerpt (pin names and nets, part order shuffled) for the footprints in the layout excerpt that follows; sources: Cadence DE-HDL packaged netlist, KiCad conversion of 04192023_DAF0TMB3IC0_F0TG_MB_C_brd_V02_OCP.brd

R6324  Q_RES  0 5% CHIP  pkg 0402LF  page 178 : A = USB_HUB2_MRP_PROG_FUNC6 ; B = USB_HUB2_TI_TEST_MRP_PROG_FUNC6
C1546  Q_CAP_DIFFBUS  DIFF BUS_0.22UF 6.3V 20% X6S  pkg C0201  page 67 : \1\ = P5E_CPU1_P3_TX_C_DN<0> ; \2\ = P5E_CPU1_P3_TX_DN<0>
PR54  Q_RES  10K 1% CHIP  pkg 0402LF  page 200 : A = PVDDCR_CPU1_P0_VMON ; B = GND

(kicad_pcb
	(version 20260206)
	(generator "pcbnew")
	(generator_version "10.0")
	(general
		(thickness 1.6)
		(legacy_teardrops no)
	)
	(paper "A4")
	(title_block
		(title "04192023_DAF0TMB3IC0_F0TG_MB_C_brd_V02_OCP.brd")
		(comment 1 "Grand Teton / footprints 4899-4901 of 8354")
	)
	(layers
		(0 "F.Cu" signal "TOP")
		(4 "In1.Cu" signal "GND")
		(6 "In2.Cu" signal "IN1")
		(8 "In3.Cu" signal "GND1")
		(10 "In4.Cu" signal "IN2")
		(12 "In5.Cu" signal "GND2")
		(14 "In6.Cu" signal "IN3")
		(16 "In7.Cu" signal "GND3")
		(18 "In8.Cu" signal "VCC")
		(20 "In9.Cu" signal "VCC1")
		(22 "In10.Cu" signal "GND4")
		(24 "In11.Cu" signal "IN4")
		(26 "In12.Cu" signal "GND5")
		(28 "In13.Cu" signal "IN5")
		(30 "In14.Cu" signal "GND6")
		(32 "In15.Cu" signal "IN6")
		(34 "In16.Cu" signal "GND7")
		(2 "B.Cu" signal "BOTTOM")
		(9 "F.Adhes" user "F.Adhesive")
		(11 "B.Adhes" user "B.Adhesive")
		(13 "F.Paste" user "Package Geometry/Pastemask Top")
		(15 "B.Paste" user "Package Geometry/Pastemask Bottom")
		(5 "F.SilkS" user "Ref Des/Silkscreen Top")
		(7 "B.SilkS" user "Ref Des/Silkscreen Bottom")
		(1 "F.Mask" user "Board Geometry/Soldermask Top")
		(3 "B.Mask" user "Board Geometry/Soldermask Bottom")
		(17 "Dwgs.User" user "User.Drawings")
		(19 "Cmts.User" user "User.Comments")
		(21 "Eco1.User" user "User.Eco1")
		(23 "Eco2.User" user "User.Eco2")
		(25 "Edge.Cuts" user "Board Geometry/Outline")
		(27 "Margin" user)
		(31 "F.CrtYd" user "Package Geometry/Place Bound Top")
		(29 "B.CrtYd" user "Package Geometry/Place Bound Bottom")
		(35 "F.Fab" user "Ref Des/Assembly Top")
		(33 "B.Fab" user "Ref Des/Assembly Bottom")
	)
	(footprint ""
		(layer "F.Cu")
		(at 105.191814 -37.6682)
		(property "Reference" "R6324"
			(at 0 0 0)
			(layer "F.SilkS")
			(hide yes)
			(effects
				(font
					(size 1.27 1.27)
				)
			)
		)
		(property "Value" ""
			(at 0 0 0)
			(layer "F.Fab")
			(effects
				(font
					(size 1.27 1.27)
				)
			)
		)
		(duplicate_pad_numbers_are_jumpers no)
		(fp_line
			(start -0.7874 -0.4064)
			(end 0.7874 -0.4064)
			(stroke
				(width 0.1524)
				(type default)
			)
			(layer "F.SilkS")
		)
		(fp_line
			(start -0.7874 0.4064)
			(end -0.7874 -0.4064)
			(stroke
				(width 0.1524)
				(type default)
			)
			(layer "F.SilkS")
		)
		(fp_line
			(start 0.7874 -0.4064)
			(end 0.7874 0.4064)
			(stroke
				(width 0.1524)
				(type default)
			)
			(layer "F.SilkS")
		)
		(fp_line
			(start 0.7874 0.4064)
			(end -0.7874 0.4064)
			(stroke
				(width 0.1524)
				(type default)
			)
			(layer "F.SilkS")
		)
		(fp_line
			(start -0.67945 -0.305054)
			(end -0.12065 -0.305054)
			(stroke
				(width 0.1)
				(type default)
			)
			(layer "F.Fab")
		)
		(fp_line
			(start -0.67945 0.3048)
			(end -0.67945 -0.305054)
			(stroke
				(width 0.1)
				(type default)
			)
			(layer "F.Fab")
		)
		(fp_line
			(start -0.12065 -0.305054)
			(end -0.12065 -0.2794)
			(stroke
				(width 0.1)
				(type default)
			)
			(layer "F.Fab")
		)
		(fp_line
			(start -0.12065 -0.2794)
			(end 0.12065 -0.2794)
			(stroke
				(width 0.1)
				(type default)
			)
			(layer "F.Fab")
		)
		(fp_line
			(start -0.12065 0.2794)
			(end -0.12065 0.3048)
			(stroke
				(width 0.1)
				(type default)
			)
			(layer "F.Fab")
		)
		(fp_line
			(start -0.12065 0.3048)
			(end -0.67945 0.3048)
			(stroke
				(width 0.1)
				(type default)
			)
			(layer "F.Fab")
		)
		(fp_line
			(start 0.120396 0.2794)
			(end -0.12065 0.2794)
			(stroke
				(width 0.1)
				(type default)
			)
			(layer "F.Fab")
		)
		(fp_line
			(start 0.120396 0.3048)
			(end 0.120396 0.2794)
			(stroke
				(width 0.1)
				(type default)
			)
			(layer "F.Fab")
		)
		(fp_line
			(start 0.12065 -0.3048)
			(end 0.67945 -0.3048)
			(stroke
				(width 0.1)
				(type default)
			)
			(layer "F.Fab")
		)
		(fp_line
			(start 0.12065 -0.2794)
			(end 0.12065 -0.3048)
			(stroke
				(width 0.1)
				(type default)
			)
			(layer "F.Fab")
		)
		(fp_line
			(start 0.67945 -0.3048)
			(end 0.67945 0.3048)
			(stroke
				(width 0.1)
				(type default)
			)
			(layer "F.Fab")
		)
		(fp_line
			(start 0.67945 0.3048)
			(end 0.120396 0.3048)
			(stroke
				(width 0.1)
				(type default)
			)
			(layer "F.Fab")
		)
		(pad "1" smd circle
			(at -0.40005 0)
			(size 0 0)
			(layers "F.Cu" "F.Mask" "F.Paste")
			(net "USB_HUB2_MRP_PROG_FUNC6")
		)
		(pad "2" smd circle
			(at 0.40005 0)
			(size 0 0)
			(layers "F.Cu" "F.Mask" "F.Paste")
			(net "USB_HUB2_TI_TEST_MRP_PROG_FUNC6")
		)
	)
	(footprint ""
		(layer "F.Cu")
		(at 318.226186 -361.061 -90)
		(property "Reference" "PR54"
			(at 0 0 270)
			(layer "F.SilkS")
			(hide yes)
			(effects
				(font
					(size 1.27 1.27)
				)
			)
		)
		(property "Value" ""
			(at 0 0 270)
			(layer "F.Fab")
			(effects
				(font
					(size 1.27 1.27)
				)
			)
		)
		(duplicate_pad_numbers_are_jumpers no)
		(fp_line
			(start -0.7874 0.4064)
			(end -0.7874 -0.4064)
			(stroke
				(width 0.1524)
				(type default)
			)
			(layer "F.SilkS")
		)
		(fp_line
			(start 0.7874 0.4064)
			(end -0.7874 0.4064)
			(stroke
				(width 0.1524)
				(type default)
			)
			(layer "F.SilkS")
		)
		(fp_line
			(start -0.7874 -0.4064)
			(end 0.7874 -0.4064)
			(stroke
				(width 0.1524)
				(type default)
			)
			(layer "F.SilkS")
		)
		(fp_line
			(start 0.7874 -0.4064)
			(end 0.7874 0.4064)
			(stroke
				(width 0.1524)
				(type default)
			)
			(layer "F.SilkS")
		)
		(fp_line
			(start -0.67945 0.3048)
			(end -0.67945 -0.305054)
			(stroke
				(width 0.1)
				(type default)
			)
			(layer "F.Fab")
		)
		(fp_line
			(start -0.12065 0.3048)
			(end -0.67945 0.3048)
			(stroke
				(width 0.1)
				(type default)
			)
			(layer "F.Fab")
		)
		(fp_line
			(start 0.120396 0.3048)
			(end 0.120396 0.2794)
			(stroke
				(width 0.1)
				(type default)
			)
			(layer "F.Fab")
		)
		(fp_line
			(start 0.67945 0.3048)
			(end 0.120396 0.3048)
			(stroke
				(width 0.1)
				(type default)
			)
			(layer "F.Fab")
		)
		(fp_line
			(start -0.12065 0.2794)
			(end -0.12065 0.3048)
			(stroke
				(width 0.1)
				(type default)
			)
			(layer "F.Fab")
		)
		(fp_line
			(start 0.120396 0.2794)
			(end -0.12065 0.2794)
			(stroke
				(width 0.1)
				(type default)
			)
			(layer "F.Fab")
		)
		(fp_line
			(start -0.12065 -0.2794)
			(end 0.12065 -0.2794)
			(stroke
				(width 0.1)
				(type default)
			)
			(layer "F.Fab")
		)
		(fp_line
			(start 0.12065 -0.2794)
			(end 0.12065 -0.3048)
			(stroke
				(width 0.1)
				(type default)
			)
			(layer "F.Fab")
		)
		(fp_line
			(start 0.12065 -0.3048)
			(end 0.67945 -0.3048)
			(stroke
				(width 0.1)
				(type default)
			)
			(layer "F.Fab")
		)
		(fp_line
			(start 0.67945 -0.3048)
			(end 0.67945 0.3048)
			(stroke
				(width 0.1)
				(type default)
			)
			(layer "F.Fab")
		)
		(fp_line
			(start -0.67945 -0.305054)
			(end -0.12065 -0.305054)
			(stroke
				(width 0.1)
				(type default)
			)
			(layer "F.Fab")
		)
		(fp_line
			(start -0.12065 -0.305054)
			(end -0.12065 -0.2794)
			(stroke
				(width 0.1)
				(type default)
			)
			(layer "F.Fab")
		)
		(pad "1" smd circle
			(at -0.40005 0 270)
			(size 0 0)
			(layers "F.Cu" "F.Mask" "F.Paste")
			(net "PVDDCR_CPU1_P0_VMON")
		)
		(pad "2" smd circle
			(at 0.40005 0 270)
			(size 0 0)
			(layers "F.Cu" "F.Mask" "F.Paste")
			(net "GND")
		)
	)
	(footprint ""
		(layer "F.Cu")
		(at 110.067344 -381.48006 180)
		(property "Reference" "C1546"
			(at 0 0 180)
			(layer "F.SilkS")
			(hide yes)
			(effects
				(font
					(size 1.27 1.27)
				)
			)
		)
		(property "Value" ""
			(at 0 0 180)
			(layer "F.Fab")
			(effects
				(font
					(size 1.27 1.27)
				)
			)
		)
		(duplicate_pad_numbers_are_jumpers no)
		(fp_line
			(start 0.299974 0.150114)
			(end -0.299974 0.150114)
			(stroke
				(width 0.1)
				(type default)
			)
			(layer "F.Fab")
		)
		(fp_line
			(start 0.299974 -0.150114)
			(end 0.299974 0.150114)
			(stroke
				(width 0.1)
				(type default)
			)
			(layer "F.Fab")
		)
		(fp_line
			(start -0.299974 0.150114)
			(end -0.299974 -0.150114)
			(stroke
				(width 0.1)
				(type default)
			)
			(layer "F.Fab")
		)
		(fp_line
			(start -0.299974 -0.150114)
			(end 0.299974 -0.150114)
			(stroke
				(width 0.1)
				(type default)
			)
			(layer "F.Fab")
		)
		(pad "1" smd rect
			(at -0.2667 0 180)
			(size 0.3048 0.381)
			(layers "F.Cu" "F.Mask" "F.Paste")
			(net "P5E_CPU1_P3_TX_C_DN<0>")
		)
		(pad "2" smd rect
			(at 0.2667 0 180)
			(size 0.3048 0.381)
			(layers "F.Cu" "F.Mask" "F.Paste")
			(net "P5E_CPU1_P3_TX_DN<0>")
		)
	)
)
